(kicad_pcb
	(version 20260206)
	(generator "pcbnew")
	(generator_version "10.0")
	(general
		(thickness 1.6)
		(legacy_teardrops no)
	)
	(paper "A4")
	(title_block
		(title "v1-chassis-manager — T6M_CM_d_v01_1031_1645.brd")
		(comment 1 "Open CloudServer (Microsoft) / footprints 1309-1317 of 2512")
	)
	(layers
		(0 "F.Cu" signal "TOP")
		(4 "In1.Cu" signal "GND1")
		(6 "In2.Cu" signal "IN1")
		(8 "In3.Cu" signal "VCC1")
		(10 "In4.Cu" signal "VCC2")
		(12 "In5.Cu" signal "GND2")
		(14 "In6.Cu" signal "IN2")
		(16 "In7.Cu" signal "IN3")
		(18 "In8.Cu" signal "GND3")
		(2 "B.Cu" signal "BOTTOM")
		(9 "F.Adhes" user "F.Adhesive")
		(11 "B.Adhes" user "B.Adhesive")
		(13 "F.Paste" user "Package Geometry/Pastemask Top")
		(15 "B.Paste" user "Package Geometry/Pastemask Bottom")
		(5 "F.SilkS" user "Ref Des/Silkscreen Top")
		(7 "B.SilkS" user "Ref Des/Silkscreen Bottom")
		(1 "F.Mask" user "Board Geometry/Soldermask Top")
		(3 "B.Mask" user "Board Geometry/Soldermask Bottom")
		(17 "Dwgs.User" user "User.Drawings")
		(19 "Cmts.User" user "User.Comments")
		(21 "Eco1.User" user "User.Eco1")
		(23 "Eco2.User" user "User.Eco2")
		(25 "Edge.Cuts" user "Board Geometry/Outline")
		(27 "Margin" user)
		(31 "F.CrtYd" user "Package Geometry/Place Bound Top")
		(29 "B.CrtYd" user "Package Geometry/Place Bound Bottom")
		(35 "F.Fab" user "Ref Des/Assembly Top")
		(33 "B.Fab" user "Ref Des/Assembly Bottom")
	)
	(footprint ""
		(layer "F.Cu")
		(at 65.77076 -178.804824 180)
		(property "Reference" "U94"
			(at 13.868908 -132.653786 90)
			(unlocked yes)
			(layer "F.SilkS")
			(effects
				(font
					(size 0.7874 0.5842)
					(thickness 0.1524)
				)
			)
		)
		(property "Value" ""
			(at 0 0 180)
			(layer "F.Fab")
			(effects
				(font
					(size 1.27 1.27)
				)
			)
		)
		(duplicate_pad_numbers_are_jumpers no)
		(fp_line
			(start 1.651 1.905)
			(end -1.651 1.905)
			(stroke
				(width 0.1524)
				(type default)
			)
			(layer "F.SilkS")
		)
		(fp_line
			(start 1.651 -1.905)
			(end 1.651 1.905)
			(stroke
				(width 0.1524)
				(type default)
			)
			(layer "F.SilkS")
		)
		(fp_line
			(start -1.651 1.905)
			(end -1.651 -1.905)
			(stroke
				(width 0.1524)
				(type default)
			)
			(layer "F.SilkS")
		)
		(fp_line
			(start -1.651 -1.905)
			(end 1.651 -1.905)
			(stroke
				(width 0.1524)
				(type default)
			)
			(layer "F.SilkS")
		)
		(fp_poly
			(pts
				(xy -1.524 0.7112) (xy -1.524 1.7526) (xy -0.508 1.7526) (xy -0.508 0.6985) (xy 0.508 0.6985) (xy 0.508 1.7526)
				(xy 1.524 1.7526) (xy 1.524 0.6985) (xy 1.524 -0.6985) (xy 0.508 -0.6985) (xy 0.508 -1.7526) (xy -0.508 -1.7526)
				(xy -0.508 -0.6985) (xy -1.524 -0.6985) (xy -1.524 0.6985)
			)
			(stroke
				(width 0)
				(type default)
			)
			(fill no)
			(layer "F.CrtYd")
		)
		(fp_text user "S"
			(at 0.254508 2.360168 0)
			(unlocked yes)
			(layer "F.SilkS")
			(effects
				(font
					(size 0.635 0.4064)
					(thickness 0.1524)
				)
			)
		)
		(fp_text user "D"
			(at -0.83693 -2.441702 0)
			(unlocked yes)
			(layer "F.SilkS")
			(effects
				(font
					(size 0.635 0.4064)
					(thickness 0.1524)
				)
			)
		)
		(fp_text user "G"
			(at -2.285492 1.979168 0)
			(unlocked yes)
			(layer "F.SilkS")
			(effects
				(font
					(size 0.635 0.4064)
					(thickness 0.1524)
				)
			)
		)
		(pad "D" smd rect
			(at 0 -1.1176 180)
			(size 1.016 1.27)
			(layers "F.Cu" "F.Mask" "F.Paste")
			(net "PSU_DC_OK_N")
		)
		(pad "G" smd rect
			(at -1.016 1.1176 180)
			(size 1.016 1.27)
			(layers "F.Cu" "F.Mask" "F.Paste")
			(net "PSU1_DC_OK_R_BUF")
		)
		(pad "S" smd rect
			(at 1.016 1.1176 180)
			(size 1.016 1.27)
			(layers "F.Cu" "F.Mask" "F.Paste")
			(net "GND")
		)
	)
	(footprint ""
		(layer "F.Cu")
		(at 65.38976 -188.126624 90)
		(property "Reference" "C643"
			(at 4.548886 -0.3175 90)
			(unlocked yes)
			(layer "F.SilkS")
			(effects
				(font
					(size 0.7874 0.5842)
					(thickness 0.1524)
				)
				(justify left)
			)
		)
		(property "Value" ""
			(at 0 0 90)
			(layer "F.Fab")
			(effects
				(font
					(size 1.27 1.27)
				)
			)
		)
		(duplicate_pad_numbers_are_jumpers no)
		(fp_line
			(start 0.7874 -0.4064)
			(end 0.7874 0.4064)
			(stroke
				(width 0.1524)
				(type default)
			)
			(layer "F.SilkS")
		)
		(fp_line
			(start -0.7874 -0.4064)
			(end 0.7874 -0.4064)
			(stroke
				(width 0.1524)
				(type default)
			)
			(layer "F.SilkS")
		)
		(fp_line
			(start 0 0.381)
			(end 0 -0.381)
			(stroke
				(width 0.1524)
				(type default)
			)
			(layer "F.SilkS")
		)
		(fp_line
			(start 0.7874 0.4064)
			(end -0.7874 0.4064)
			(stroke
				(width 0.1524)
				(type default)
			)
			(layer "F.SilkS")
		)
		(fp_line
			(start -0.7874 0.4064)
			(end -0.7874 -0.4064)
			(stroke
				(width 0.1524)
				(type default)
			)
			(layer "F.SilkS")
		)
		(fp_poly
			(pts
				(xy -0.5334 0.254) (xy -0.635 0.254) (xy -0.635 0.2286) (xy -0.635 -0.254) (xy -0.5334 -0.254) (xy -0.5334 -0.2794)
				(xy 0.5334 -0.2794) (xy 0.5334 -0.254) (xy 0.635 -0.254) (xy 0.635 0.254) (xy 0.5334 0.254) (xy 0.5334 0.2794)
				(xy -0.508 0.2794) (xy -0.5334 0.2794)
			)
			(stroke
				(width 0)
				(type default)
			)
			(fill no)
			(layer "F.CrtYd")
		)
		(pad "1" smd rect
			(at 0.40005 0 90)
			(size 0.4572 0.508)
			(layers "F.Cu" "F.Mask" "F.Paste")
			(net "T2_NODE4_EN_R")
		)
		(pad "2" smd rect
			(at -0.40005 0 90)
			(size 0.4572 0.508)
			(layers "F.Cu" "F.Mask" "F.Paste")
			(net "GND")
		)
	)
	(footprint ""
		(layer "F.Cu")
		(at 53.95976 -188.126624 90)
		(property "Reference" "C587"
			(at 4.548886 0.375158 90)
			(unlocked yes)
			(layer "F.SilkS")
			(effects
				(font
					(size 0.7874 0.5842)
					(thickness 0.1524)
				)
				(justify left)
			)
		)
		(property "Value" ""
			(at 0 0 90)
			(layer "F.Fab")
			(effects
				(font
					(size 1.27 1.27)
				)
			)
		)
		(duplicate_pad_numbers_are_jumpers no)
		(fp_line
			(start 0.7874 -0.4064)
			(end 0.7874 0.4064)
			(stroke
				(width 0.1524)
				(type default)
			)
			(layer "F.SilkS")
		)
		(fp_line
			(start -0.7874 -0.4064)
			(end 0.7874 -0.4064)
			(stroke
				(width 0.1524)
				(type default)
			)
			(layer "F.SilkS")
		)
		(fp_line
			(start 0 0.381)
			(end 0 -0.381)
			(stroke
				(width 0.1524)
				(type default)
			)
			(layer "F.SilkS")
		)
		(fp_line
			(start 0.7874 0.4064)
			(end -0.7874 0.4064)
			(stroke
				(width 0.1524)
				(type default)
			)
			(layer "F.SilkS")
		)
		(fp_line
			(start -0.7874 0.4064)
			(end -0.7874 -0.4064)
			(stroke
				(width 0.1524)
				(type default)
			)
			(layer "F.SilkS")
		)
		(fp_poly
			(pts
				(xy -0.5334 0.254) (xy -0.635 0.254) (xy -0.635 0.2286) (xy -0.635 -0.254) (xy -0.5334 -0.254) (xy -0.5334 -0.2794)
				(xy 0.5334 -0.2794) (xy 0.5334 -0.254) (xy 0.635 -0.254) (xy 0.635 0.254) (xy 0.5334 0.254) (xy 0.5334 0.2794)
				(xy -0.508 0.2794) (xy -0.5334 0.2794)
			)
			(stroke
				(width 0)
				(type default)
			)
			(fill no)
			(layer "F.CrtYd")
		)
		(pad "1" smd rect
			(at 0.40005 0 90)
			(size 0.4572 0.508)
			(layers "F.Cu" "F.Mask" "F.Paste")
			(net "I2C_PSU1_R_SDA")
		)
		(pad "2" smd rect
			(at -0.40005 0 90)
			(size 0.4572 0.508)
			(layers "F.Cu" "F.Mask" "F.Paste")
			(net "GND")
		)
	)
	(footprint ""
		(layer "F.Cu")
		(at 19.938746 -97.973388 180)
		(property "Reference" "R1153"
			(at 5.192776 0.307086 0)
			(unlocked yes)
			(layer "F.SilkS")
			(effects
				(font
					(size 0.7874 0.5842)
					(thickness 0.1524)
				)
				(justify left)
			)
		)
		(property "Value" ""
			(at 0 0 180)
			(layer "F.Fab")
			(effects
				(font
					(size 1.27 1.27)
				)
			)
		)
		(duplicate_pad_numbers_are_jumpers no)
		(fp_line
			(start 0.7874 0.4064)
			(end -0.7874 0.4064)
			(stroke
				(width 0.1524)
				(type default)
			)
			(layer "F.SilkS")
		)
		(fp_line
			(start 0.7874 -0.4064)
			(end 0.7874 0.4064)
			(stroke
				(width 0.1524)
				(type default)
			)
			(layer "F.SilkS")
		)
		(fp_line
			(start -0.7874 0.4064)
			(end -0.7874 -0.4064)
			(stroke
				(width 0.1524)
				(type default)
			)
			(layer "F.SilkS")
		)
		(fp_line
			(start -0.7874 -0.4064)
			(end 0.7874 -0.4064)
			(stroke
				(width 0.1524)
				(type default)
			)
			(layer "F.SilkS")
		)
		(fp_poly
			(pts
				(xy -0.508 0.2794) (xy -0.508 0.2286) (xy -0.635 0.2286) (xy -0.635 -0.254) (xy -0.5334 -0.254)
				(xy -0.5334 -0.2794) (xy 0.5334 -0.2794) (xy 0.5334 -0.254) (xy 0.635 -0.254) (xy 0.635 0.254) (xy 0.5334 0.254)
				(xy 0.5334 0.2794)
			)
			(stroke
				(width 0)
				(type default)
			)
			(fill no)
			(layer "F.CrtYd")
		)
		(pad "1" smd rect
			(at 0.40005 0 180)
			(size 0.4572 0.508)
			(layers "F.Cu" "F.Mask" "F.Paste")
			(net "GND")
		)
		(pad "2" smd rect
			(at -0.40005 0 180)
			(size 0.4572 0.508)
			(layers "F.Cu" "F.Mask" "F.Paste")
			(net "FRU_SYS_A1")
		)
	)
	(footprint ""
		(layer "F.Cu")
		(at 82.96656 -80.683608 -90)
		(property "Reference" "C88"
			(at 17.592294 -1.189482 90)
			(unlocked yes)
			(layer "F.SilkS")
			(effects
				(font
					(size 0.7874 0.5842)
					(thickness 0.1524)
				)
				(justify left)
			)
		)
		(property "Value" ""
			(at 0 0 270)
			(layer "F.Fab")
			(effects
				(font
					(size 1.27 1.27)
				)
			)
		)
		(duplicate_pad_numbers_are_jumpers no)
		(fp_line
			(start -0.7874 0.4064)
			(end -0.7874 -0.4064)
			(stroke
				(width 0.1524)
				(type default)
			)
			(layer "F.SilkS")
		)
		(fp_line
			(start 0.7874 0.4064)
			(end -0.7874 0.4064)
			(stroke
				(width 0.1524)
				(type default)
			)
			(layer "F.SilkS")
		)
		(fp_line
			(start 0 0.381)
			(end 0 -0.381)
			(stroke
				(width 0.1524)
				(type default)
			)
			(layer "F.SilkS")
		)
		(fp_line
			(start -0.7874 -0.4064)
			(end 0.7874 -0.4064)
			(stroke
				(width 0.1524)
				(type default)
			)
			(layer "F.SilkS")
		)
		(fp_line
			(start 0.7874 -0.4064)
			(end 0.7874 0.4064)
			(stroke
				(width 0.1524)
				(type default)
			)
			(layer "F.SilkS")
		)
		(fp_poly
			(pts
				(xy -0.5334 0.254) (xy -0.635 0.254) (xy -0.635 0.2286) (xy -0.635 -0.254) (xy -0.5334 -0.254) (xy -0.5334 -0.2794)
				(xy 0.5334 -0.2794) (xy 0.5334 -0.254) (xy 0.635 -0.254) (xy 0.635 0.254) (xy 0.5334 0.254) (xy 0.5334 0.2794)
				(xy -0.508 0.2794) (xy -0.5334 0.2794)
			)
			(stroke
				(width 0)
				(type default)
			)
			(fill no)
			(layer "F.CrtYd")
		)
		(pad "1" smd rect
			(at 0.40005 0 270)
			(size 0.4572 0.508)
			(layers "F.Cu" "F.Mask" "F.Paste")
			(net "PV_VCCP_NODE1")
		)
		(pad "2" smd rect
			(at -0.40005 0 270)
			(size 0.4572 0.508)
			(layers "F.Cu" "F.Mask" "F.Paste")
			(net "GND")
		)
	)
	(footprint ""
		(layer "F.Cu")
		(at 174.636684 -41.493186 180)
		(property "Reference" "U53"
			(at -2.365248 0.11176 90)
			(unlocked yes)
			(layer "F.SilkS")
			(effects
				(font
					(size 0.7874 0.5842)
					(thickness 0.1524)
				)
			)
		)
		(property "Value" ""
			(at 0 0 180)
			(layer "F.Fab")
			(effects
				(font
					(size 1.27 1.27)
				)
			)
		)
		(duplicate_pad_numbers_are_jumpers no)
		(fp_line
			(start 1.549908 2.032)
			(end -1.549908 2.032)
			(stroke
				(width 0.1524)
				(type default)
			)
			(layer "F.SilkS")
		)
		(fp_line
			(start 1.549908 -2.032)
			(end 1.549908 2.032)
			(stroke
				(width 0.1524)
				(type default)
			)
			(layer "F.SilkS")
		)
		(fp_line
			(start -1.549908 2.032)
			(end -1.549908 -2.032)
			(stroke
				(width 0.1524)
				(type default)
			)
			(layer "F.SilkS")
		)
		(fp_line
			(start -1.549908 -2.032)
			(end 1.549908 -2.032)
			(stroke
				(width 0.1524)
				(type default)
			)
			(layer "F.SilkS")
		)
		(fp_poly
			(pts
				(xy -0.94996 2.4765) (xy -1.33096 3.6195) (xy -0.56896 3.6195)
			)
			(stroke
				(width 0)
				(type default)
			)
			(fill yes)
			(layer "F.SilkS")
		)
		(fp_poly
			(pts
				(xy -1.1684 1.905) (xy -1.1684 0.8636) (xy -1.5494 0.8636) (xy -1.5494 -0.8636) (xy -1.1684 -0.8636)
				(xy -1.1684 -1.905) (xy 1.1684 -1.905) (xy 1.1684 -0.8636) (xy 1.5494 -0.8636) (xy 1.5494 0.8636)
				(xy 1.1684 0.8636) (xy 1.1684 1.905)
			)
			(stroke
				(width 0)
				(type default)
			)
			(fill no)
			(layer "F.CrtYd")
		)
		(pad "1" smd rect
			(at -0.94996 1.225042 180)
			(size 0.4064 1.3208)
			(layers "F.Cu" "F.Mask" "F.Paste")
			(net "USB1_L_DN")
		)
		(pad "2" smd rect
			(at 0 1.225042 180)
			(size 0.4064 1.3208)
			(layers "F.Cu" "F.Mask" "F.Paste")
			(net "GND")
		)
		(pad "3" smd rect
			(at 0.94996 1.225042 180)
			(size 0.4064 1.3208)
			(layers "F.Cu" "F.Mask" "F.Paste")
			(net "USB1_L_DP")
		)
		(pad "4" smd rect
			(at 0.94996 -1.225042 180)
			(size 0.4064 1.3208)
			(layers "F.Cu" "F.Mask" "F.Paste")
			(net "USB0_L_DP")
		)
		(pad "5" smd rect
			(at 0 -1.225042 180)
			(size 0.4064 1.3208)
			(layers "F.Cu" "F.Mask" "F.Paste")
			(net "USBPWR_P0")
		)
		(pad "6" smd rect
			(at -0.94996 -1.225042 180)
			(size 0.4064 1.3208)
			(layers "F.Cu" "F.Mask" "F.Paste")
			(net "USB0_L_DN")
		)
	)
	(footprint ""
		(layer "F.Cu")
		(at 62.934596 -151.481028 180)
		(property "Reference" "R555"
			(at 30.839664 6.20141 0)
			(unlocked yes)
			(layer "F.SilkS")
			(effects
				(font
					(size 0.7874 0.5842)
					(thickness 0.1524)
				)
				(justify left)
			)
		)
		(property "Value" ""
			(at 0 0 180)
			(layer "F.Fab")
			(effects
				(font
					(size 1.27 1.27)
				)
			)
		)
		(duplicate_pad_numbers_are_jumpers no)
		(fp_line
			(start 0.7874 0.4064)
			(end -0.7874 0.4064)
			(stroke
				(width 0.1524)
				(type default)
			)
			(layer "F.SilkS")
		)
		(fp_line
			(start 0.7874 -0.4064)
			(end 0.7874 0.4064)
			(stroke
				(width 0.1524)
				(type default)
			)
			(layer "F.SilkS")
		)
		(fp_line
			(start -0.7874 0.4064)
			(end -0.7874 -0.4064)
			(stroke
				(width 0.1524)
				(type default)
			)
			(layer "F.SilkS")
		)
		(fp_line
			(start -0.7874 -0.4064)
			(end 0.7874 -0.4064)
			(stroke
				(width 0.1524)
				(type default)
			)
			(layer "F.SilkS")
		)
		(fp_poly
			(pts
				(xy -0.508 0.2794) (xy -0.508 0.2286) (xy -0.635 0.2286) (xy -0.635 -0.254) (xy -0.5334 -0.254)
				(xy -0.5334 -0.2794) (xy 0.5334 -0.2794) (xy 0.5334 -0.254) (xy 0.635 -0.254) (xy 0.635 0.254) (xy 0.5334 0.254)
				(xy 0.5334 0.2794)
			)
			(stroke
				(width 0)
				(type default)
			)
			(fill no)
			(layer "F.CrtYd")
		)
		(pad "1" smd rect
			(at 0.40005 0 180)
			(size 0.4572 0.508)
			(layers "F.Cu" "F.Mask" "F.Paste")
			(net "LAN1_NVM_WP_N")
		)
		(pad "2" smd rect
			(at -0.40005 0 180)
			(size 0.4572 0.508)
			(layers "F.Cu" "F.Mask" "F.Paste")
			(net "P3V3_NODE1")
		)
	)
	(footprint ""
		(layer "F.Cu")
		(at 45.557694 -102.399084 90)
		(property "Reference" "R198"
			(at -2.331212 -2.549652 90)
			(unlocked yes)
			(layer "F.SilkS")
			(effects
				(font
					(size 0.7874 0.5842)
					(thickness 0.1524)
				)
				(justify left)
			)
		)
		(property "Value" ""
			(at 0 0 90)
			(layer "F.Fab")
			(effects
				(font
					(size 1.27 1.27)
				)
			)
		)
		(duplicate_pad_numbers_are_jumpers no)
		(fp_line
			(start 0.7874 -0.4064)
			(end 0.7874 0.4064)
			(stroke
				(width 0.1524)
				(type default)
			)
			(layer "F.SilkS")
		)
		(fp_line
			(start -0.7874 -0.4064)
			(end 0.7874 -0.4064)
			(stroke
				(width 0.1524)
				(type default)
			)
			(layer "F.SilkS")
		)
		(fp_line
			(start 0.7874 0.4064)
			(end -0.7874 0.4064)
			(stroke
				(width 0.1524)
				(type default)
			)
			(layer "F.SilkS")
		)
		(fp_line
			(start -0.7874 0.4064)
			(end -0.7874 -0.4064)
			(stroke
				(width 0.1524)
				(type default)
			)
			(layer "F.SilkS")
		)
		(fp_poly
			(pts
				(xy -0.508 0.2794) (xy -0.508 0.2286) (xy -0.635 0.2286) (xy -0.635 -0.254) (xy -0.5334 -0.254)
				(xy -0.5334 -0.2794) (xy 0.5334 -0.2794) (xy 0.5334 -0.254) (xy 0.635 -0.254) (xy 0.635 0.254) (xy 0.5334 0.254)
				(xy 0.5334 0.2794)
			)
			(stroke
				(width 0)
				(type default)
			)
			(fill no)
			(layer "F.CrtYd")
		)
		(pad "1" smd rect
			(at 0.40005 0 90)
			(size 0.4572 0.508)
			(layers "F.Cu" "F.Mask" "F.Paste")
			(net "P3V3_NODE1")
		)
		(pad "2" smd rect
			(at -0.40005 0 90)
			(size 0.4572 0.508)
			(layers "F.Cu" "F.Mask" "F.Paste")
			(net "SMB_TEMP1_NODE1_ALERT_R_L")
		)
	)
	(footprint ""
		(layer "F.Cu")
		(at 103.589836 -138.90117 90)
		(property "Reference" "PR78"
			(at 4.973828 -1.973834 0)
			(unlocked yes)
			(layer "F.SilkS")
			(effects
				(font
					(size 0.635 0.4064)
					(thickness 0.1524)
				)
				(justify left)
			)
		)
		(property "Value" ""
			(at 0 0 90)
			(layer "F.Fab")
			(effects
				(font
					(size 1.27 1.27)
				)
			)
		)
		(duplicate_pad_numbers_are_jumpers no)
		(fp_line
			(start 0.7874 -0.4064)
			(end 0.7874 0.4064)
			(stroke
				(width 0.1524)
				(type default)
			)
			(layer "F.SilkS")
		)
		(fp_line
			(start -0.7874 -0.4064)
			(end 0.7874 -0.4064)
			(stroke
				(width 0.1524)
				(type default)
			)
			(layer "F.SilkS")
		)
		(fp_line
			(start 0.7874 0.4064)
			(end -0.7874 0.4064)
			(stroke
				(width 0.1524)
				(type default)
			)
			(layer "F.SilkS")
		)
		(fp_line
			(start -0.7874 0.4064)
			(end -0.7874 -0.4064)
			(stroke
				(width 0.1524)
				(type default)
			)
			(layer "F.SilkS")
		)
		(fp_poly
			(pts
				(xy -0.508 0.2794) (xy -0.508 0.2286) (xy -0.635 0.2286) (xy -0.635 -0.254) (xy -0.5334 -0.254)
				(xy -0.5334 -0.2794) (xy 0.5334 -0.2794) (xy 0.5334 -0.254) (xy 0.635 -0.254) (xy 0.635 0.254) (xy 0.5334 0.254)
				(xy 0.5334 0.2794)
			)
			(stroke
				(width 0)
				(type default)
			)
			(fill no)
			(layer "F.CrtYd")
		)
		(pad "1" smd rect
			(at 0.40005 0 90)
			(size 0.4572 0.508)
			(layers "F.Cu" "F.Mask" "F.Paste")
			(net "AGND_PVCCP_NODE1")
		)
		(pad "2" smd rect
			(at -0.40005 0 90)
			(size 0.4572 0.508)
			(layers "F.Cu" "F.Mask" "F.Paste")
			(net "VR_PVCCP_NODE1_IBIAS")
		)
	)
)
